# S9S_MB_2U (Grand Teton) — schematic netlist excerpt (pin names and nets, part order shuffled) for the footprints in the layout excerpt that follows; sources: Cadence DE-HDL packaged netlist, KiCad conversion of 03242023_DA0F0TMBIJ0_F0T_Motherboard_J_brd_V01_OCP.brd

R2926  Q_RES  4.7K 5% CHIP  pkg 0402LF  page 151 : A = BMC_MONITER_BUF_R ; B = GND
R4451  Q_RES  33.2 1% EMPTY  pkg 0402LF  page 196 : A = RST_USB_HUB_N ; B = RST_USB_HUB_2_R_N

(kicad_pcb
	(version 20260206)
	(generator "pcbnew")
	(generator_version "10.0")
	(general
		(thickness 1.6)
		(legacy_teardrops no)
	)
	(paper "A4")
	(title_block
		(title "03242023_DA0F0TMBIJ0_F0T_Motherboard_J_brd_V01_OCP.brd")
		(comment 1 "Grand Teton / footprints 2958-2959 of 6105")
	)
	(layers
		(0 "F.Cu" signal "TOP")
		(4 "In1.Cu" signal "GND")
		(6 "In2.Cu" signal "IN1")
		(8 "In3.Cu" signal "GND1")
		(10 "In4.Cu" signal "IN2")
		(12 "In5.Cu" signal "GND2")
		(14 "In6.Cu" signal "IN3")
		(16 "In7.Cu" signal "GND3")
		(18 "In8.Cu" signal "VCC")
		(20 "In9.Cu" signal "VCC1")
		(22 "In10.Cu" signal "GND4")
		(24 "In11.Cu" signal "IN4")
		(26 "In12.Cu" signal "GND5")
		(28 "In13.Cu" signal "IN5")
		(30 "In14.Cu" signal "GND6")
		(32 "In15.Cu" signal "IN6")
		(34 "In16.Cu" signal "GND7")
		(2 "B.Cu" signal "BOTTOM")
		(9 "F.Adhes" user "F.Adhesive")
		(11 "B.Adhes" user "B.Adhesive")
		(13 "F.Paste" user "Package Geometry/Pastemask Top")
		(15 "B.Paste" user "Package Geometry/Pastemask Bottom")
		(5 "F.SilkS" user "Ref Des/Silkscreen Top")
		(7 "B.SilkS" user "Ref Des/Silkscreen Bottom")
		(1 "F.Mask" user "Board Geometry/Soldermask Top")
		(3 "B.Mask" user "Board Geometry/Soldermask Bottom")
		(17 "Dwgs.User" user "User.Drawings")
		(19 "Cmts.User" user "User.Comments")
		(21 "Eco1.User" user "User.Eco1")
		(23 "Eco2.User" user "User.Eco2")
		(25 "Edge.Cuts" user "Board Geometry/Outline")
		(27 "Margin" user)
		(31 "F.CrtYd" user "Package Geometry/Place Bound Top")
		(29 "B.CrtYd" user "Package Geometry/Place Bound Bottom")
		(35 "F.Fab" user "Ref Des/Assembly Top")
		(33 "B.Fab" user "Ref Des/Assembly Bottom")
	)
	(footprint ""
		(layer "F.Cu")
		(at 176.17948 -427.446948)
		(property "Reference" "R2926"
			(at 0 0 0)
			(layer "F.SilkS")
			(hide yes)
			(effects
				(font
					(size 1.27 1.27)
				)
			)
		)
		(property "Value" ""
			(at 0 0 0)
			(layer "F.Fab")
			(effects
				(font
					(size 1.27 1.27)
				)
			)
		)
		(duplicate_pad_numbers_are_jumpers no)
		(fp_line
			(start -0.7874 -0.4064)
			(end 0.7874 -0.4064)
			(stroke
				(width 0.1524)
				(type default)
			)
			(layer "F.SilkS")
		)
		(fp_line
			(start -0.7874 0.4064)
			(end -0.7874 -0.4064)
			(stroke
				(width 0.1524)
				(type default)
			)
			(layer "F.SilkS")
		)
		(fp_line
			(start 0.7874 -0.4064)
			(end 0.7874 0.4064)
			(stroke
				(width 0.1524)
				(type default)
			)
			(layer "F.SilkS")
		)
		(fp_line
			(start 0.7874 0.4064)
			(end -0.7874 0.4064)
			(stroke
				(width 0.1524)
				(type default)
			)
			(layer "F.SilkS")
		)
		(fp_line
			(start -0.67945 -0.305054)
			(end -0.12065 -0.305054)
			(stroke
				(width 0.1)
				(type default)
			)
			(layer "F.Fab")
		)
		(fp_line
			(start -0.67945 0.3048)
			(end -0.67945 -0.305054)
			(stroke
				(width 0.1)
				(type default)
			)
			(layer "F.Fab")
		)
		(fp_line
			(start -0.12065 -0.305054)
			(end -0.12065 -0.2794)
			(stroke
				(width 0.1)
				(type default)
			)
			(layer "F.Fab")
		)
		(fp_line
			(start -0.12065 -0.2794)
			(end 0.12065 -0.2794)
			(stroke
				(width 0.1)
				(type default)
			)
			(layer "F.Fab")
		)
		(fp_line
			(start -0.12065 0.2794)
			(end -0.12065 0.3048)
			(stroke
				(width 0.1)
				(type default)
			)
			(layer "F.Fab")
		)
		(fp_line
			(start -0.12065 0.3048)
			(end -0.67945 0.3048)
			(stroke
				(width 0.1)
				(type default)
			)
			(layer "F.Fab")
		)
		(fp_line
			(start 0.120396 0.2794)
			(end -0.12065 0.2794)
			(stroke
				(width 0.1)
				(type default)
			)
			(layer "F.Fab")
		)
		(fp_line
			(start 0.120396 0.3048)
			(end 0.120396 0.2794)
			(stroke
				(width 0.1)
				(type default)
			)
			(layer "F.Fab")
		)
		(fp_line
			(start 0.12065 -0.3048)
			(end 0.67945 -0.3048)
			(stroke
				(width 0.1)
				(type default)
			)
			(layer "F.Fab")
		)
		(fp_line
			(start 0.12065 -0.2794)
			(end 0.12065 -0.3048)
			(stroke
				(width 0.1)
				(type default)
			)
			(layer "F.Fab")
		)
		(fp_line
			(start 0.67945 -0.3048)
			(end 0.67945 0.3048)
			(stroke
				(width 0.1)
				(type default)
			)
			(layer "F.Fab")
		)
		(fp_line
			(start 0.67945 0.3048)
			(end 0.120396 0.3048)
			(stroke
				(width 0.1)
				(type default)
			)
			(layer "F.Fab")
		)
		(pad "1" smd circle
			(at -0.40005 0)
			(size 0 0)
			(layers "F.Cu" "F.Mask" "F.Paste")
			(net "BMC_MONITER_BUF_R")
		)
		(pad "2" smd circle
			(at 0.40005 0)
			(size 0 0)
			(layers "F.Cu" "F.Mask" "F.Paste")
			(net "GND")
		)
	)
	(footprint ""
		(layer "F.Cu")
		(at 152.978612 -31.341568 90)
		(property "Reference" "R4451"
			(at 0 0 90)
			(layer "F.SilkS")
			(hide yes)
			(effects
				(font
					(size 1.27 1.27)
				)
			)
		)
		(property "Value" ""
			(at 0 0 90)
			(layer "F.Fab")
			(effects
				(font
					(size 1.27 1.27)
				)
			)
		)
		(duplicate_pad_numbers_are_jumpers no)
		(fp_line
			(start 0.7874 -0.4064)
			(end 0.7874 0.4064)
			(stroke
				(width 0.1524)
				(type default)
			)
			(layer "F.SilkS")
		)
		(fp_line
			(start -0.7874 -0.4064)
			(end 0.7874 -0.4064)
			(stroke
				(width 0.1524)
				(type default)
			)
			(layer "F.SilkS")
		)
		(fp_line
			(start 0.7874 0.4064)
			(end -0.7874 0.4064)
			(stroke
				(width 0.1524)
				(type default)
			)
			(layer "F.SilkS")
		)
		(fp_line
			(start -0.7874 0.4064)
			(end -0.7874 -0.4064)
			(stroke
				(width 0.1524)
				(type default)
			)
			(layer "F.SilkS")
		)
		(fp_line
			(start -0.12065 -0.305054)
			(end -0.12065 -0.2794)
			(stroke
				(width 0.1)
				(type default)
			)
			(layer "F.Fab")
		)
		(fp_line
			(start -0.67945 -0.305054)
			(end -0.12065 -0.305054)
			(stroke
				(width 0.1)
				(type default)
			)
			(layer "F.Fab")
		)
		(fp_line
			(start 0.67945 -0.3048)
			(end 0.67945 0.3048)
			(stroke
				(width 0.1)
				(type default)
			)
			(layer "F.Fab")
		)
		(fp_line
			(start 0.12065 -0.3048)
			(end 0.67945 -0.3048)
			(stroke
				(width 0.1)
				(type default)
			)
			(layer "F.Fab")
		)
		(fp_line
			(start 0.12065 -0.2794)
			(end 0.12065 -0.3048)
			(stroke
				(width 0.1)
				(type default)
			)
			(layer "F.Fab")
		)
		(fp_line
			(start -0.12065 -0.2794)
			(end 0.12065 -0.2794)
			(stroke
				(width 0.1)
				(type default)
			)
			(layer "F.Fab")
		)
		(fp_line
			(start 0.120396 0.2794)
			(end -0.12065 0.2794)
			(stroke
				(width 0.1)
				(type default)
			)
			(layer "F.Fab")
		)
		(fp_line
			(start -0.12065 0.2794)
			(end -0.12065 0.3048)
			(stroke
				(width 0.1)
				(type default)
			)
			(layer "F.Fab")
		)
		(fp_line
			(start 0.67945 0.3048)
			(end 0.120396 0.3048)
			(stroke
				(width 0.1)
				(type default)
			)
			(layer "F.Fab")
		)
		(fp_line
			(start 0.120396 0.3048)
			(end 0.120396 0.2794)
			(stroke
				(width 0.1)
				(type default)
			)
			(layer "F.Fab")
		)
		(fp_line
			(start -0.12065 0.3048)
			(end -0.67945 0.3048)
			(stroke
				(width 0.1)
				(type default)
			)
			(layer "F.Fab")
		)
		(fp_line
			(start -0.67945 0.3048)
			(end -0.67945 -0.305054)
			(stroke
				(width 0.1)
				(type default)
			)
			(layer "F.Fab")
		)
		(pad "1" smd circle
			(at -0.40005 0 90)
			(size 0 0)
			(layers "F.Cu" "F.Mask" "F.Paste")
			(net "RST_USB_HUB_N")
		)
		(pad "2" smd circle
			(at 0.40005 0 90)
			(size 0 0)
			(layers "F.Cu" "F.Mask" "F.Paste")
			(net "RST_USB_HUB_2_R_N")
		)
	)
)
